(kicad_pcb
	(version 20260206)
	(generator "pcbnew")
	(generator_version "10.0")
	(general
		(thickness 1.6)
		(legacy_teardrops no)
	)
	(paper "A4")
	(title_block
		(title "Wiwynn_Tioga_Pass_MB.brd")
		(comment 1 "Tioga Pass / footprint 1727 of 4770 (EU1B1), pads 1-41 of 41")
	)
	(layers
		(0 "F.Cu" signal "TOP")
		(4 "In1.Cu" signal "L2GND")
		(6 "In2.Cu" signal "L3")
		(8 "In3.Cu" signal "L4GND")
		(10 "In4.Cu" signal "L5")
		(12 "In5.Cu" signal "L6GND")
		(14 "In6.Cu" signal "L7VCC")
		(16 "In7.Cu" signal "L8VCC")
		(18 "In8.Cu" signal "L9GND")
		(20 "In9.Cu" signal "L10")
		(22 "In10.Cu" signal "L11GND")
		(24 "In11.Cu" signal "L12")
		(26 "In12.Cu" signal "L13GND")
		(2 "B.Cu" signal "BOTTOM")
		(9 "F.Adhes" user "F.Adhesive")
		(11 "B.Adhes" user "B.Adhesive")
		(13 "F.Paste" user "Package Geometry/Pastemask Top")
		(15 "B.Paste" user "Package Geometry/Pastemask Bottom")
		(5 "F.SilkS" user "Ref Des/Silkscreen Top")
		(7 "B.SilkS" user "Ref Des/Silkscreen Bottom")
		(1 "F.Mask" user "Board Geometry/Soldermask Top")
		(3 "B.Mask" user "Board Geometry/Soldermask Bottom")
		(17 "Dwgs.User" user "User.Drawings")
		(19 "Cmts.User" user "User.Comments")
		(21 "Eco1.User" user "User.Eco1")
		(23 "Eco2.User" user "User.Eco2")
		(25 "Edge.Cuts" user "Board Geometry/Outline")
		(27 "Margin" user)
		(31 "F.CrtYd" user "Package Geometry/Place Bound Top")
		(29 "B.CrtYd" user "Package Geometry/Place Bound Bottom")
		(35 "F.Fab" user "Ref Des/Assembly Top")
		(33 "B.Fab" user "Ref Des/Assembly Bottom")
	)
	(footprint ""
		(layer "F.Cu")
		(at 2.0574 -127.9652 -90)
		(property "Reference" "EU1B1"
			(at 3.76047 4.0132 0)
			(unlocked yes)
			(layer "F.SilkS")
			(effects
				(font
					(size 0.7874 0.5842)
					(thickness 0.1524)
				)
				(justify left)
			)
		)
		(property "Value" ""
			(at 0 0 270)
			(layer "F.Fab")
			(effects
				(font
					(size 1.27 1.27)
				)
			)
		)
		(duplicate_pad_numbers_are_jumpers no)
		(pad "1" smd custom
			(at -2.4511 -1.800098 270)
			(size 0.0508 0.0508)
			(layers "F.Cu" "F.Mask" "F.Paste")
			(net "Net_287")
			(options
				(clearance outline)
				(anchor circle)
			)
			(primitives
				(gr_poly
					(pts
						(arc
							(start 0.254 -0.1016)
							(mid 0.3556 0)
							(end 0.254 0.1016)
						)
						(xy -0.3556 0.1016) (xy -0.3556 -0.1016)
					)
					(width 0)
					(fill yes)
				)
			)
		)
		(pad "2" smd custom
			(at -2.4511 -1.400048 270)
			(size 0.0508 0.0508)
			(layers "F.Cu" "F.Mask" "F.Paste")
			(net "Net_271")
			(options
				(clearance outline)
				(anchor circle)
			)
			(primitives
				(gr_poly
					(pts
						(arc
							(start 0.254 -0.1016)
							(mid 0.3556 0)
							(end 0.254 0.1016)
						)
						(xy -0.3556 0.1016) (xy -0.3556 -0.1016)
					)
					(width 0)
					(fill yes)
				)
			)
		)
		(pad "3" smd custom
			(at -2.4511 -0.999998 270)
			(size 0.0508 0.0508)
			(layers "F.Cu" "F.Mask" "F.Paste")
			(net "Net_250")
			(options
				(clearance outline)
				(anchor circle)
			)
			(primitives
				(gr_poly
					(pts
						(arc
							(start 0.254 -0.1016)
							(mid 0.3556 0)
							(end 0.254 0.1016)
						)
						(xy -0.3556 0.1016) (xy -0.3556 -0.1016)
					)
					(width 0)
					(fill yes)
				)
			)
		)
		(pad "4" smd custom
			(at -2.4511 -0.599948 270)
			(size 0.0508 0.0508)
			(layers "F.Cu" "F.Mask" "F.Paste")
			(net "VR_PVDDQ_KLM_PWM2")
			(options
				(clearance outline)
				(anchor circle)
			)
			(primitives
				(gr_poly
					(pts
						(arc
							(start 0.254 -0.1016)
							(mid 0.3556 0)
							(end 0.254 0.1016)
						)
						(xy -0.3556 0.1016) (xy -0.3556 -0.1016)
					)
					(width 0)
					(fill yes)
				)
			)
		)
		(pad "5" smd custom
			(at -2.4511 -0.199898 270)
			(size 0.0508 0.0508)
			(layers "F.Cu" "F.Mask" "F.Paste")
			(net "VR_PVDDQ_KLM_PWM1")
			(options
				(clearance outline)
				(anchor circle)
			)
			(primitives
				(gr_poly
					(pts
						(arc
							(start 0.254 -0.1016)
							(mid 0.3556 0)
							(end 0.254 0.1016)
						)
						(xy -0.3556 0.1016) (xy -0.3556 -0.1016)
					)
					(width 0)
					(fill yes)
				)
			)
		)
		(pad "6" smd custom
			(at -2.4511 0.199898 270)
			(size 0.0508 0.0508)
			(layers "F.Cu" "F.Mask" "F.Paste")
			(net "SMB_VR_STBY_LVC3_SDA")
			(options
				(clearance outline)
				(anchor circle)
			)
			(primitives
				(gr_poly
					(pts
						(arc
							(start 0.254 -0.1016)
							(mid 0.3556 0)
							(end 0.254 0.1016)
						)
						(xy -0.3556 0.1016) (xy -0.3556 -0.1016)
					)
					(width 0)
					(fill yes)
				)
			)
		)
		(pad "7" smd custom
			(at -2.4511 0.599948 270)
			(size 0.0508 0.0508)
			(layers "F.Cu" "F.Mask" "F.Paste")
			(net "SMB_VR_STBY_LVC3_SCL")
			(options
				(clearance outline)
				(anchor circle)
			)
			(primitives
				(gr_poly
					(pts
						(arc
							(start 0.254 -0.1016)
							(mid 0.3556 0)
							(end 0.254 0.1016)
						)
						(xy -0.3556 0.1016) (xy -0.3556 -0.1016)
					)
					(width 0)
					(fill yes)
				)
			)
		)
		(pad "8" smd custom
			(at -2.4511 0.999998 270)
			(size 0.0508 0.0508)
			(layers "F.Cu" "F.Mask" "F.Paste")
			(net "Net_288")
			(options
				(clearance outline)
				(anchor circle)
			)
			(primitives
				(gr_poly
					(pts
						(arc
							(start 0.254 -0.1016)
							(mid 0.3556 0)
							(end 0.254 0.1016)
						)
						(xy -0.3556 0.1016) (xy -0.3556 -0.1016)
					)
					(width 0)
					(fill yes)
				)
			)
		)
		(pad "9" smd custom
			(at -2.4511 1.400048 270)
			(size 0.0508 0.0508)
			(layers "F.Cu" "F.Mask" "F.Paste")
			(net "PWRGD_PVDDQ_KLM_R")
			(options
				(clearance outline)
				(anchor circle)
			)
			(primitives
				(gr_poly
					(pts
						(arc
							(start 0.254 -0.1016)
							(mid 0.3556 0)
							(end 0.254 0.1016)
						)
						(xy -0.3556 0.1016) (xy -0.3556 -0.1016)
					)
					(width 0)
					(fill yes)
				)
			)
		)
		(pad "10" smd custom
			(at -2.4511 1.800098 270)
			(size 0.0508 0.0508)
			(layers "F.Cu" "F.Mask" "F.Paste")
			(net "VR_PVDDQ_KLM_VREN")
			(options
				(clearance outline)
				(anchor circle)
			)
			(primitives
				(gr_poly
					(pts
						(arc
							(start 0.254 -0.1016)
							(mid 0.3556 0)
							(end 0.254 0.1016)
						)
						(xy -0.3556 0.1016) (xy -0.3556 -0.1016)
					)
					(width 0)
					(fill yes)
				)
			)
		)
		(pad "11" smd custom
			(at -1.800098 2.4511 270)
			(size 0.0508 0.0508)
			(layers "F.Cu" "F.Mask" "F.Paste")
			(net "IRQ_PVDDQ_KLM_VRHOT_LVT3_R_N")
			(options
				(clearance outline)
				(anchor circle)
			)
			(primitives
				(gr_poly
					(pts
						(arc
							(start -0.1016 -0.254)
							(mid 0 -0.3556)
							(end 0.1016 -0.254)
						)
						(xy 0.1016 0.3556) (xy -0.1016 0.3556)
					)
					(width 0)
					(fill yes)
				)
			)
		)
		(pad "12" smd custom
			(at -1.400048 2.4511 270)
			(size 0.0508 0.0508)
			(layers "F.Cu" "F.Mask" "F.Paste")
			(net "Net_239")
			(options
				(clearance outline)
				(anchor circle)
			)
			(primitives
				(gr_poly
					(pts
						(arc
							(start -0.1016 -0.254)
							(mid 0 -0.3556)
							(end 0.1016 -0.254)
						)
						(xy 0.1016 0.3556) (xy -0.1016 0.3556)
					)
					(width 0)
					(fill yes)
				)
			)
		)
		(pad "13" smd custom
			(at -0.999998 2.4511 270)
			(size 0.0508 0.0508)
			(layers "F.Cu" "F.Mask" "F.Paste")
			(net "PU_VR_PVDDQ_KLM_FAULT1")
			(options
				(clearance outline)
				(anchor circle)
			)
			(primitives
				(gr_poly
					(pts
						(arc
							(start -0.1016 -0.254)
							(mid 0 -0.3556)
							(end 0.1016 -0.254)
						)
						(xy 0.1016 0.3556) (xy -0.1016 0.3556)
					)
					(width 0)
					(fill yes)
				)
			)
		)
		(pad "14" smd custom
			(at -0.599948 2.4511 270)
			(size 0.0508 0.0508)
			(layers "F.Cu" "F.Mask" "F.Paste")
			(net "NC_PVDDQ_KLM_GP1")
			(options
				(clearance outline)
				(anchor circle)
			)
			(primitives
				(gr_poly
					(pts
						(arc
							(start -0.1016 -0.254)
							(mid 0 -0.3556)
							(end 0.1016 -0.254)
						)
						(xy 0.1016 0.3556) (xy -0.1016 0.3556)
					)
					(width 0)
					(fill yes)
				)
			)
		)
		(pad "15" smd custom
			(at -0.199898 2.4511 270)
			(size 0.0508 0.0508)
			(layers "F.Cu" "F.Mask" "F.Paste")
			(net "SVID_CLK_PVDDQ_KLM")
			(options
				(clearance outline)
				(anchor circle)
			)
			(primitives
				(gr_poly
					(pts
						(arc
							(start -0.1016 -0.254)
							(mid 0 -0.3556)
							(end 0.1016 -0.254)
						)
						(xy 0.1016 0.3556) (xy -0.1016 0.3556)
					)
					(width 0)
					(fill yes)
				)
			)
		)
		(pad "16" smd custom
			(at 0.199898 2.4511 270)
			(size 0.0508 0.0508)
			(layers "F.Cu" "F.Mask" "F.Paste")
			(net "SVID_VDIO_PVDDQ_KLM")
			(options
				(clearance outline)
				(anchor circle)
			)
			(primitives
				(gr_poly
					(pts
						(arc
							(start -0.1016 -0.254)
							(mid 0 -0.3556)
							(end 0.1016 -0.254)
						)
						(xy 0.1016 0.3556) (xy -0.1016 0.3556)
					)
					(width 0)
					(fill yes)
				)
			)
		)
		(pad "17" smd custom
			(at 0.599948 2.4511 270)
			(size 0.0508 0.0508)
			(layers "F.Cu" "F.Mask" "F.Paste")
			(net "SVID_ALERT_PVDDQ_KLM")
			(options
				(clearance outline)
				(anchor circle)
			)
			(primitives
				(gr_poly
					(pts
						(arc
							(start -0.1016 -0.254)
							(mid 0 -0.3556)
							(end 0.1016 -0.254)
						)
						(xy 0.1016 0.3556) (xy -0.1016 0.3556)
					)
					(width 0)
					(fill yes)
				)
			)
		)
		(pad "18" smd custom
			(at 0.999998 2.4511 270)
			(size 0.0508 0.0508)
			(layers "F.Cu" "F.Mask" "F.Paste")
			(net "NC_PVDDQ_KLM_GP0")
			(options
				(clearance outline)
				(anchor circle)
			)
			(primitives
				(gr_poly
					(pts
						(arc
							(start -0.1016 -0.254)
							(mid 0 -0.3556)
							(end 0.1016 -0.254)
						)
						(xy 0.1016 0.3556) (xy -0.1016 0.3556)
					)
					(width 0)
					(fill yes)
				)
			)
		)
		(pad "19" smd custom
			(at 1.400048 2.4511 270)
			(size 0.0508 0.0508)
			(layers "F.Cu" "F.Mask" "F.Paste")
			(net "VR_PVDDQ_KLM_AVSP")
			(options
				(clearance outline)
				(anchor circle)
			)
			(primitives
				(gr_poly
					(pts
						(arc
							(start -0.1016 -0.254)
							(mid 0 -0.3556)
							(end 0.1016 -0.254)
						)
						(xy 0.1016 0.3556) (xy -0.1016 0.3556)
					)
					(width 0)
					(fill yes)
				)
			)
		)
		(pad "20" smd custom
			(at 1.800098 2.4511 270)
			(size 0.0508 0.0508)
			(layers "F.Cu" "F.Mask" "F.Paste")
			(net "VSENSE_PVDDQ_KLM_N")
			(options
				(clearance outline)
				(anchor circle)
			)
			(primitives
				(gr_poly
					(pts
						(arc
							(start -0.1016 -0.254)
							(mid 0 -0.3556)
							(end 0.1016 -0.254)
						)
						(xy 0.1016 0.3556) (xy -0.1016 0.3556)
					)
					(width 0)
					(fill yes)
				)
			)
		)
		(pad "21" smd custom
			(at 2.4511 1.800098 270)
			(size 0.0508 0.0508)
			(layers "F.Cu" "F.Mask" "F.Paste")
			(net "VR_PVDDQ_KLM_AIREF1")
			(options
				(clearance outline)
				(anchor circle)
			)
			(primitives
				(gr_poly
					(pts
						(arc
							(start -0.254 0.1016)
							(mid -0.3556 0)
							(end -0.254 -0.1016)
						)
						(xy 0.3556 -0.1016) (xy 0.3556 0.1016)
					)
					(width 0)
					(fill yes)
				)
			)
		)
		(pad "22" smd custom
			(at 2.4511 1.400048 270)
			(size 0.0508 0.0508)
			(layers "F.Cu" "F.Mask" "F.Paste")
			(net "ISENSE_PVDDQ_KLM_PH1_IMON")
			(options
				(clearance outline)
				(anchor circle)
			)
			(primitives
				(gr_poly
					(pts
						(arc
							(start -0.254 0.1016)
							(mid -0.3556 0)
							(end -0.254 -0.1016)
						)
						(xy 0.3556 -0.1016) (xy 0.3556 0.1016)
					)
					(width 0)
					(fill yes)
				)
			)
		)
		(pad "23" smd custom
			(at 2.4511 0.999998 270)
			(size 0.0508 0.0508)
			(layers "F.Cu" "F.Mask" "F.Paste")
			(net "VR_PVDDQ_KLM_AIREF2")
			(options
				(clearance outline)
				(anchor circle)
			)
			(primitives
				(gr_poly
					(pts
						(arc
							(start -0.254 0.1016)
							(mid -0.3556 0)
							(end -0.254 -0.1016)
						)
						(xy 0.3556 -0.1016) (xy 0.3556 0.1016)
					)
					(width 0)
					(fill yes)
				)
			)
		)
		(pad "24" smd custom
			(at 2.4511 0.599948 270)
			(size 0.0508 0.0508)
			(layers "F.Cu" "F.Mask" "F.Paste")
			(net "ISENSE_PVDDQ_KLM_PH2_IMON")
			(options
				(clearance outline)
				(anchor circle)
			)
			(primitives
				(gr_poly
					(pts
						(arc
							(start -0.254 0.1016)
							(mid -0.3556 0)
							(end -0.254 -0.1016)
						)
						(xy 0.3556 -0.1016) (xy 0.3556 0.1016)
					)
					(width 0)
					(fill yes)
				)
			)
		)
		(pad "25" smd custom
			(at 2.4511 0.199898 270)
			(size 0.0508 0.0508)
			(layers "F.Cu" "F.Mask" "F.Paste")
			(net "Net_249")
			(options
				(clearance outline)
				(anchor circle)
			)
			(primitives
				(gr_poly
					(pts
						(arc
							(start -0.254 0.1016)
							(mid -0.3556 0)
							(end -0.254 -0.1016)
						)
						(xy 0.3556 -0.1016) (xy 0.3556 0.1016)
					)
					(width 0)
					(fill yes)
				)
			)
		)
		(pad "26" smd custom
			(at 2.4511 -0.199898 270)
			(size 0.0508 0.0508)
			(layers "F.Cu" "F.Mask" "F.Paste")
			(net "Net_248")
			(options
				(clearance outline)
				(anchor circle)
			)
			(primitives
				(gr_poly
					(pts
						(arc
							(start -0.254 0.1016)
							(mid -0.3556 0)
							(end -0.254 -0.1016)
						)
						(xy 0.3556 -0.1016) (xy 0.3556 0.1016)
					)
					(width 0)
					(fill yes)
				)
			)
		)
		(pad "27" smd custom
			(at 2.4511 -0.599948 270)
			(size 0.0508 0.0508)
			(layers "F.Cu" "F.Mask" "F.Paste")
			(net "GND")
			(options
				(clearance outline)
				(anchor circle)
			)
			(primitives
				(gr_poly
					(pts
						(arc
							(start -0.254 0.1016)
							(mid -0.3556 0)
							(end -0.254 -0.1016)
						)
						(xy 0.3556 -0.1016) (xy 0.3556 0.1016)
					)
					(width 0)
					(fill yes)
				)
			)
		)
		(pad "28" smd custom
			(at 2.4511 -0.999998 270)
			(size 0.0508 0.0508)
			(layers "F.Cu" "F.Mask" "F.Paste")
			(net "Net_272")
			(options
				(clearance outline)
				(anchor circle)
			)
			(primitives
				(gr_poly
					(pts
						(arc
							(start -0.254 0.1016)
							(mid -0.3556 0)
							(end -0.254 -0.1016)
						)
						(xy 0.3556 -0.1016) (xy 0.3556 0.1016)
					)
					(width 0)
					(fill yes)
				)
			)
		)
		(pad "29" smd custom
			(at 2.4511 -1.400048 270)
			(size 0.0508 0.0508)
			(layers "F.Cu" "F.Mask" "F.Paste")
			(net "Net_238")
			(options
				(clearance outline)
				(anchor circle)
			)
			(primitives
				(gr_poly
					(pts
						(arc
							(start -0.254 0.1016)
							(mid -0.3556 0)
							(end -0.254 -0.1016)
						)
						(xy 0.3556 -0.1016) (xy 0.3556 0.1016)
					)
					(width 0)
					(fill yes)
				)
			)
		)
		(pad "30" smd custom
			(at 2.4511 -1.800098 270)
			(size 0.0508 0.0508)
			(layers "F.Cu" "F.Mask" "F.Paste")
			(net "Net_237")
			(options
				(clearance outline)
				(anchor circle)
			)
			(primitives
				(gr_poly
					(pts
						(arc
							(start -0.254 0.1016)
							(mid -0.3556 0)
							(end -0.254 -0.1016)
						)
						(xy 0.3556 -0.1016) (xy 0.3556 0.1016)
					)
					(width 0)
					(fill yes)
				)
			)
		)
		(pad "31" smd custom
			(at 1.800098 -2.4511 270)
			(size 0.0508 0.0508)
			(layers "F.Cu" "F.Mask" "F.Paste")
			(net "Net_235")
			(options
				(clearance outline)
				(anchor circle)
			)
			(primitives
				(gr_poly
					(pts
						(arc
							(start 0.1016 0.254)
							(mid 0 0.3556)
							(end -0.1016 0.254)
						)
						(xy -0.1016 -0.3556) (xy 0.1016 -0.3556)
					)
					(width 0)
					(fill yes)
				)
			)
		)
		(pad "32" smd custom
			(at 1.400048 -2.4511 270)
			(size 0.0508 0.0508)
			(layers "F.Cu" "F.Mask" "F.Paste")
			(net "GND")
			(options
				(clearance outline)
				(anchor circle)
			)
			(primitives
				(gr_poly
					(pts
						(arc
							(start 0.1016 0.254)
							(mid 0 0.3556)
							(end -0.1016 0.254)
						)
						(xy -0.1016 -0.3556) (xy 0.1016 -0.3556)
					)
					(width 0)
					(fill yes)
				)
			)
		)
		(pad "33" smd custom
			(at 0.999998 -2.4511 270)
			(size 0.0508 0.0508)
			(layers "F.Cu" "F.Mask" "F.Paste")
			(net "VR_PVDDQ_KLM_XADDR2")
			(options
				(clearance outline)
				(anchor circle)
			)
			(primitives
				(gr_poly
					(pts
						(arc
							(start 0.1016 0.254)
							(mid 0 0.3556)
							(end -0.1016 0.254)
						)
						(xy -0.1016 -0.3556) (xy 0.1016 -0.3556)
					)
					(width 0)
					(fill yes)
				)
			)
		)
		(pad "34" smd custom
			(at 0.599948 -2.4511 270)
			(size 0.0508 0.0508)
			(layers "F.Cu" "F.Mask" "F.Paste")
			(net "Net_236")
			(options
				(clearance outline)
				(anchor circle)
			)
			(primitives
				(gr_poly
					(pts
						(arc
							(start 0.1016 0.254)
							(mid 0 0.3556)
							(end -0.1016 0.254)
						)
						(xy -0.1016 -0.3556) (xy 0.1016 -0.3556)
					)
					(width 0)
					(fill yes)
				)
			)
		)
		(pad "35" smd custom
			(at 0.199898 -2.4511 270)
			(size 0.0508 0.0508)
			(layers "F.Cu" "F.Mask" "F.Paste")
			(net "A_TSENSE_PVDDQ_KLM")
			(options
				(clearance outline)
				(anchor circle)
			)
			(primitives
				(gr_poly
					(pts
						(arc
							(start 0.1016 0.254)
							(mid 0 0.3556)
							(end -0.1016 0.254)
						)
						(xy -0.1016 -0.3556) (xy 0.1016 -0.3556)
					)
					(width 0)
					(fill yes)
				)
			)
		)
		(pad "36" smd custom
			(at -0.199898 -2.4511 270)
			(size 0.0508 0.0508)
			(layers "F.Cu" "F.Mask" "F.Paste")
			(net "VR_PVDDQ_KLM_XADDR1")
			(options
				(clearance outline)
				(anchor circle)
			)
			(primitives
				(gr_poly
					(pts
						(arc
							(start 0.1016 0.254)
							(mid 0 0.3556)
							(end -0.1016 0.254)
						)
						(xy -0.1016 -0.3556) (xy 0.1016 -0.3556)
					)
					(width 0)
					(fill yes)
				)
			)
		)
		(pad "37" smd custom
			(at -0.599948 -2.4511 270)
			(size 0.0508 0.0508)
			(layers "F.Cu" "F.Mask" "F.Paste")
			(net "VR_PVDDQ_KLM_VINSEN")
			(options
				(clearance outline)
				(anchor circle)
			)
			(primitives
				(gr_poly
					(pts
						(arc
							(start 0.1016 0.254)
							(mid 0 0.3556)
							(end -0.1016 0.254)
						)
						(xy -0.1016 -0.3556) (xy 0.1016 -0.3556)
					)
					(width 0)
					(fill yes)
				)
			)
		)
		(pad "38" smd custom
			(at -0.999998 -2.4511 270)
			(size 0.0508 0.0508)
			(layers "F.Cu" "F.Mask" "F.Paste")
			(net "VR_PVDDQ_KLM_AIINSEN")
			(options
				(clearance outline)
				(anchor circle)
			)
			(primitives
				(gr_poly
					(pts
						(arc
							(start 0.1016 0.254)
							(mid 0 0.3556)
							(end -0.1016 0.254)
						)
						(xy -0.1016 -0.3556) (xy 0.1016 -0.3556)
					)
					(width 0)
					(fill yes)
				)
			)
		)
		(pad "39" smd custom
			(at -1.400048 -2.4511 270)
			(size 0.0508 0.0508)
			(layers "F.Cu" "F.Mask" "F.Paste")
			(net "VR_PVDDQ_KLM_VDD")
			(options
				(clearance outline)
				(anchor circle)
			)
			(primitives
				(gr_poly
					(pts
						(arc
							(start 0.1016 0.254)
							(mid 0 0.3556)
							(end -0.1016 0.254)
						)
						(xy -0.1016 -0.3556) (xy 0.1016 -0.3556)
					)
					(width 0)
					(fill yes)
				)
			)
		)
		(pad "40" smd custom
			(at -1.800098 -2.4511 270)
			(size 0.0508 0.0508)
			(layers "F.Cu" "F.Mask" "F.Paste")
			(net "VR_PVDDQ_KLM_VD12")
			(options
				(clearance outline)
				(anchor circle)
			)
			(primitives
				(gr_poly
					(pts
						(arc
							(start 0.1016 0.254)
							(mid 0 0.3556)
							(end -0.1016 0.254)
						)
						(xy -0.1016 -0.3556) (xy 0.1016 -0.3556)
					)
					(width 0)
					(fill yes)
				)
			)
		)
		(pad "41" smd rect
			(at 0 0 270)
			(size 3.683 3.683)
			(layers "F.Cu" "F.Mask" "F.Paste")
			(net "GND")
		)
	)
)
